# T6G (Grand Teton) — schematic netlist excerpt (pin names and nets, part order shuffled) for the footprints in the layout excerpt that follows; sources: Cadence DE-HDL packaged netlist, KiCad conversion of 04192023_DAF0TMB3IC0_F0TG_MB_C_brd_V02_OCP.brd

R1279  Q_RES  33 5% CHIP  pkg 0402LF  page 81 : A = FM_P1_PCC1_N ; B = FM_P1_PCC1_R_N

U75  74LVC1G17GW  IC  pkg TSSOP5  page 133
  NC  = NC
  A  = RST_PERST_OCP_SFF_BUF_N
  GND  = GND
  Y  = RST_PERST_OCP_SFF_BUF2_N
  VCC  = P3V3_AUX

PC1898  Q_CAP  22UF 16V 20% X6S  pkg C0805  page 189 : A = SW_P5V_AUX_FLT ; B = GND

(kicad_pcb
	(version 20260206)
	(generator "pcbnew")
	(generator_version "10.0")
	(general
		(thickness 1.6)
		(legacy_teardrops no)
	)
	(paper "A4")
	(title_block
		(title "04192023_DAF0TMB3IC0_F0TG_MB_C_brd_V02_OCP.brd")
		(comment 1 "Grand Teton / footprints 1066-1068 of 8354")
	)
	(layers
		(0 "F.Cu" signal "TOP")
		(4 "In1.Cu" signal "GND")
		(6 "In2.Cu" signal "IN1")
		(8 "In3.Cu" signal "GND1")
		(10 "In4.Cu" signal "IN2")
		(12 "In5.Cu" signal "GND2")
		(14 "In6.Cu" signal "IN3")
		(16 "In7.Cu" signal "GND3")
		(18 "In8.Cu" signal "VCC")
		(20 "In9.Cu" signal "VCC1")
		(22 "In10.Cu" signal "GND4")
		(24 "In11.Cu" signal "IN4")
		(26 "In12.Cu" signal "GND5")
		(28 "In13.Cu" signal "IN5")
		(30 "In14.Cu" signal "GND6")
		(32 "In15.Cu" signal "IN6")
		(34 "In16.Cu" signal "GND7")
		(2 "B.Cu" signal "BOTTOM")
		(9 "F.Adhes" user "F.Adhesive")
		(11 "B.Adhes" user "B.Adhesive")
		(13 "F.Paste" user "Package Geometry/Pastemask Top")
		(15 "B.Paste" user "Package Geometry/Pastemask Bottom")
		(5 "F.SilkS" user "Ref Des/Silkscreen Top")
		(7 "B.SilkS" user "Ref Des/Silkscreen Bottom")
		(1 "F.Mask" user "Board Geometry/Soldermask Top")
		(3 "B.Mask" user "Board Geometry/Soldermask Bottom")
		(17 "Dwgs.User" user "User.Drawings")
		(19 "Cmts.User" user "User.Comments")
		(21 "Eco1.User" user "User.Eco1")
		(23 "Eco2.User" user "User.Eco2")
		(25 "Edge.Cuts" user "Board Geometry/Outline")
		(27 "Margin" user)
		(31 "F.CrtYd" user "Package Geometry/Place Bound Top")
		(29 "B.CrtYd" user "Package Geometry/Place Bound Bottom")
		(35 "F.Fab" user "Ref Des/Assembly Top")
		(33 "B.Fab" user "Ref Des/Assembly Bottom")
	)
	(footprint ""
		(layer "F.Cu")
		(at 209.628232 -124.21997)
		(property "Reference" "U75"
			(at -2.433574 -2.925318 0)
			(unlocked yes)
			(layer "F.SilkS")
			(effects
				(font
					(size 0.7874 0.5842)
					(thickness 0.1524)
				)
				(justify left)
			)
		)
		(property "Value" ""
			(at 0 0 0)
			(layer "F.Fab")
			(effects
				(font
					(size 1.27 1.27)
				)
			)
		)
		(duplicate_pad_numbers_are_jumpers no)
		(fp_line
			(start -1.695958 -1.124966)
			(end 1.695958 -1.124966)
			(stroke
				(width 0.1524)
				(type default)
			)
			(layer "F.SilkS")
		)
		(fp_line
			(start -1.695958 1.124966)
			(end -1.695958 -1.124966)
			(stroke
				(width 0.1524)
				(type default)
			)
			(layer "F.SilkS")
		)
		(fp_line
			(start 1.695958 -1.124966)
			(end 1.695958 1.124966)
			(stroke
				(width 0.1524)
				(type default)
			)
			(layer "F.SilkS")
		)
		(fp_line
			(start 1.695958 1.124966)
			(end -1.695958 1.124966)
			(stroke
				(width 0.1524)
				(type default)
			)
			(layer "F.SilkS")
		)
		(fp_poly
			(pts
				(xy -2.935478 -0.403352) (xy -2.935478 -1.023112) (xy -2.315718 -0.713232)
			)
			(stroke
				(width 0)
				(type default)
			)
			(fill yes)
			(layer "F.SilkS")
		)
		(fp_line
			(start -0.674878 -1.124966)
			(end 0.674878 -1.124966)
			(stroke
				(width 0.1)
				(type default)
			)
			(layer "F.Fab")
		)
		(fp_line
			(start -0.674878 1.124966)
			(end -0.674878 -1.124966)
			(stroke
				(width 0.1)
				(type default)
			)
			(layer "F.Fab")
		)
		(fp_line
			(start 0.674878 -1.124966)
			(end 0.674878 1.124966)
			(stroke
				(width 0.1)
				(type default)
			)
			(layer "F.Fab")
		)
		(fp_line
			(start 0.674878 1.124966)
			(end -0.674878 1.124966)
			(stroke
				(width 0.1)
				(type default)
			)
			(layer "F.Fab")
		)
		(fp_poly
			(pts
				(xy -2.4892 -0.959866) (xy -1.86944 -0.649986) (xy -2.4892 -0.340106)
			)
			(stroke
				(width 0)
				(type default)
			)
			(fill yes)
			(layer "F.Fab")
		)
		(pad "1" smd rect
			(at -0.94488 -0.649986 90)
			(size 0.3556 1.2446)
			(layers "F.Cu" "F.Mask" "F.Paste")
			(net "Net_10785")
		)
		(pad "2" smd rect
			(at -0.94488 0 90)
			(size 0.3556 1.2446)
			(layers "F.Cu" "F.Mask" "F.Paste")
			(net "RST_PERST_OCP_SFF_BUF_N")
		)
		(pad "3" smd rect
			(at -0.94488 0.649986 90)
			(size 0.3556 1.2446)
			(layers "F.Cu" "F.Mask" "F.Paste")
			(net "GND")
		)
		(pad "4" smd rect
			(at 0.94488 0.649986 90)
			(size 0.3556 1.2446)
			(layers "F.Cu" "F.Mask" "F.Paste")
			(net "RST_PERST_OCP_SFF_BUF2_N")
		)
		(pad "5" smd rect
			(at 0.94488 -0.649986 90)
			(size 0.3556 1.2446)
			(layers "F.Cu" "F.Mask" "F.Paste")
			(net "P3V3_AUX")
		)
	)
	(footprint ""
		(layer "F.Cu")
		(at 182.757572 -133.561074 -90)
		(property "Reference" "R1279"
			(at 0 0 270)
			(layer "F.SilkS")
			(hide yes)
			(effects
				(font
					(size 1.27 1.27)
				)
			)
		)
		(property "Value" ""
			(at 0 0 270)
			(layer "F.Fab")
			(effects
				(font
					(size 1.27 1.27)
				)
			)
		)
		(duplicate_pad_numbers_are_jumpers no)
		(fp_line
			(start -0.7874 0.4064)
			(end -0.7874 -0.4064)
			(stroke
				(width 0.1524)
				(type default)
			)
			(layer "F.SilkS")
		)
		(fp_line
			(start 0.7874 0.4064)
			(end -0.7874 0.4064)
			(stroke
				(width 0.1524)
				(type default)
			)
			(layer "F.SilkS")
		)
		(fp_line
			(start -0.7874 -0.4064)
			(end 0.7874 -0.4064)
			(stroke
				(width 0.1524)
				(type default)
			)
			(layer "F.SilkS")
		)
		(fp_line
			(start 0.7874 -0.4064)
			(end 0.7874 0.4064)
			(stroke
				(width 0.1524)
				(type default)
			)
			(layer "F.SilkS")
		)
		(fp_line
			(start -0.67945 0.3048)
			(end -0.67945 -0.305054)
			(stroke
				(width 0.1)
				(type default)
			)
			(layer "F.Fab")
		)
		(fp_line
			(start -0.12065 0.3048)
			(end -0.67945 0.3048)
			(stroke
				(width 0.1)
				(type default)
			)
			(layer "F.Fab")
		)
		(fp_line
			(start 0.120396 0.3048)
			(end 0.120396 0.2794)
			(stroke
				(width 0.1)
				(type default)
			)
			(layer "F.Fab")
		)
		(fp_line
			(start 0.67945 0.3048)
			(end 0.120396 0.3048)
			(stroke
				(width 0.1)
				(type default)
			)
			(layer "F.Fab")
		)
		(fp_line
			(start -0.12065 0.2794)
			(end -0.12065 0.3048)
			(stroke
				(width 0.1)
				(type default)
			)
			(layer "F.Fab")
		)
		(fp_line
			(start 0.120396 0.2794)
			(end -0.12065 0.2794)
			(stroke
				(width 0.1)
				(type default)
			)
			(layer "F.Fab")
		)
		(fp_line
			(start -0.12065 -0.2794)
			(end 0.12065 -0.2794)
			(stroke
				(width 0.1)
				(type default)
			)
			(layer "F.Fab")
		)
		(fp_line
			(start 0.12065 -0.2794)
			(end 0.12065 -0.3048)
			(stroke
				(width 0.1)
				(type default)
			)
			(layer "F.Fab")
		)
		(fp_line
			(start 0.12065 -0.3048)
			(end 0.67945 -0.3048)
			(stroke
				(width 0.1)
				(type default)
			)
			(layer "F.Fab")
		)
		(fp_line
			(start 0.67945 -0.3048)
			(end 0.67945 0.3048)
			(stroke
				(width 0.1)
				(type default)
			)
			(layer "F.Fab")
		)
		(fp_line
			(start -0.67945 -0.305054)
			(end -0.12065 -0.305054)
			(stroke
				(width 0.1)
				(type default)
			)
			(layer "F.Fab")
		)
		(fp_line
			(start -0.12065 -0.305054)
			(end -0.12065 -0.2794)
			(stroke
				(width 0.1)
				(type default)
			)
			(layer "F.Fab")
		)
		(pad "1" smd circle
			(at -0.40005 0 270)
			(size 0 0)
			(layers "F.Cu" "F.Mask" "F.Paste")
			(net "FM_P1_PCC1_N")
		)
		(pad "2" smd circle
			(at 0.40005 0 270)
			(size 0 0)
			(layers "F.Cu" "F.Mask" "F.Paste")
			(net "FM_P1_PCC1_R_N")
		)
	)
	(footprint ""
		(layer "F.Cu")
		(at 413.928306 -137.16762)
		(property "Reference" "PC1898"
			(at 0 0 0)
			(layer "F.SilkS")
			(hide yes)
			(effects
				(font
					(size 1.27 1.27)
				)
			)
		)
		(property "Value" ""
			(at 0 0 0)
			(layer "F.Fab")
			(effects
				(font
					(size 1.27 1.27)
				)
			)
		)
		(duplicate_pad_numbers_are_jumpers no)
		(fp_line
			(start -1.524 -0.762)
			(end 1.524 -0.762)
			(stroke
				(width 0.1524)
				(type default)
			)
			(layer "F.SilkS")
		)
		(fp_line
			(start -1.524 0.762)
			(end -1.524 -0.762)
			(stroke
				(width 0.1524)
				(type default)
			)
			(layer "F.SilkS")
		)
		(fp_line
			(start 1.524 -0.762)
			(end 1.524 0.762)
			(stroke
				(width 0.1524)
				(type default)
			)
			(layer "F.SilkS")
		)
		(fp_line
			(start 1.524 0.762)
			(end -1.524 0.762)
			(stroke
				(width 0.1524)
				(type default)
			)
			(layer "F.SilkS")
		)
		(fp_line
			(start -1.1049 -0.724916)
			(end -1.1049 0.724916)
			(stroke
				(width 0.1)
				(type default)
			)
			(layer "F.Fab")
		)
		(fp_line
			(start -1.1049 0.724916)
			(end 1.1049 0.724916)
			(stroke
				(width 0.1)
				(type default)
			)
			(layer "F.Fab")
		)
		(fp_line
			(start 1.1049 -0.724916)
			(end -1.1049 -0.724916)
			(stroke
				(width 0.1)
				(type default)
			)
			(layer "F.Fab")
		)
		(fp_line
			(start 1.1049 0.724916)
			(end 1.1049 -0.724916)
			(stroke
				(width 0.1)
				(type default)
			)
			(layer "F.Fab")
		)
		(pad "1" smd rect
			(at -0.889 0 180)
			(size 1.016 1.27)
			(layers "F.Cu" "F.Mask" "F.Paste")
			(net "SW_P5V_AUX_FLT")
		)
		(pad "2" smd rect
			(at 0.889 0 180)
			(size 1.016 1.27)
			(layers "F.Cu" "F.Mask" "F.Paste")
			(net "GND")
		)
	)
)
